(kicad_pcb
	(version 20260206)
	(generator "pcbnew")
	(generator_version "10.0")
	(general
		(thickness 1.6)
		(legacy_teardrops no)
	)
	(paper "A4")
	(title_block
		(title "v2-pdb — ms_pdb_v2.brd")
		(comment 1 "Open CloudServer (Microsoft) / footprint 341 of 348 (J14), pads 1-46 of 46")
	)
	(layers
		(0 "F.Cu" signal "TOP")
		(4 "In1.Cu" signal "GND")
		(6 "In2.Cu" signal "IN1")
		(8 "In3.Cu" signal "VCC")
		(10 "In4.Cu" signal "VCC1")
		(12 "In5.Cu" signal "IN2")
		(14 "In6.Cu" signal "GND1")
		(2 "B.Cu" signal "BOTTOM")
		(9 "F.Adhes" user "F.Adhesive")
		(11 "B.Adhes" user "B.Adhesive")
		(13 "F.Paste" user "Package Geometry/Pastemask Top")
		(15 "B.Paste" user "Package Geometry/Pastemask Bottom")
		(5 "F.SilkS" user "Ref Des/Silkscreen Top")
		(7 "B.SilkS" user "Ref Des/Silkscreen Bottom")
		(1 "F.Mask" user "Board Geometry/Soldermask Top")
		(3 "B.Mask" user "Board Geometry/Soldermask Bottom")
		(17 "Dwgs.User" user "User.Drawings")
		(19 "Cmts.User" user "User.Comments")
		(21 "Eco1.User" user "User.Eco1")
		(23 "Eco2.User" user "User.Eco2")
		(25 "Edge.Cuts" user "Board Geometry/Outline")
		(27 "Margin" user)
		(31 "F.CrtYd" user "Package Geometry/Place Bound Top")
		(29 "B.CrtYd" user "Package Geometry/Place Bound Bottom")
		(35 "F.Fab" user "Ref Des/Assembly Top")
		(33 "B.Fab" user "Ref Des/Assembly Bottom")
	)
	(footprint ""
		(layer "B.Cu")
		(at 44.03979 -319.41008 90)
		(property "Reference" "J14"
			(at 6.291834 -4.21005 0)
			(unlocked yes)
			(layer "B.SilkS")
			(effects
				(font
					(size 0.7874 0.5842)
					(thickness 0.1524)
				)
				(justify left mirror)
			)
		)
		(property "Value" ""
			(at 0 0 90)
			(layer "B.Fab")
			(effects
				(font
					(size 1.27 1.27)
				)
				(justify mirror)
			)
		)
		(duplicate_pad_numbers_are_jumpers no)
		(pad "" np_thru_hole circle
			(at -1.35001 -2.54)
			(size 2.5146 2.5146)
			(drill 2.5146)
			(layers "*.Cu" "*.Mask")
			(clearance 0.381)
			(thermal_gap 0.381)
		)
		(pad "" np_thru_hole circle
			(at 0 50.8)
			(size 2.5146 2.5146)
			(drill 2.5146)
			(layers "*.Cu" "*.Mask")
			(clearance 0.381)
			(thermal_gap 0.381)
		)
		(pad "P1" thru_hole rect
			(at 0 0)
			(size 1.1684 1.1684)
			(drill 0.762)
			(layers "*.Cu" "*.Mask")
			(remove_unused_layers no)
			(net "GND")
			(clearance 0.0508)
			(padstack
				(mode front_inner_back)
				(layer "Inner"
					(shape circle)
					(size 1.1684 1.1684)
					(clearance 0.0508)
				)
				(layer "B.Cu"
					(shape rect)
					(size 1.1684 1.1684)
					(thermal_gap 0.0508)
					(clearance 0.0508)
				)
			)
		)
		(pad "P2" thru_hole circle
			(at 0 2.54)
			(size 1.1684 1.1684)
			(drill 0.762)
			(layers "*.Cu" "*.Mask")
			(remove_unused_layers no)
			(net "GND")
			(clearance 0.0508)
			(thermal_gap 0.0508)
		)
		(pad "P3" thru_hole circle
			(at 0 5.08)
			(size 1.1684 1.1684)
			(drill 0.762)
			(layers "*.Cu" "*.Mask")
			(remove_unused_layers no)
			(net "GND")
			(clearance 0.0508)
			(thermal_gap 0.0508)
		)
		(pad "P4" thru_hole circle
			(at 0 7.62)
			(size 1.1684 1.1684)
			(drill 0.762)
			(layers "*.Cu" "*.Mask")
			(remove_unused_layers no)
			(net "GND")
			(clearance 0.0508)
			(thermal_gap 0.0508)
		)
		(pad "P5" thru_hole circle
			(at 0 10.16)
			(size 1.1684 1.1684)
			(drill 0.762)
			(layers "*.Cu" "*.Mask")
			(remove_unused_layers no)
			(net "GND")
			(clearance 0.0508)
			(thermal_gap 0.0508)
		)
		(pad "P6" thru_hole circle
			(at 0 12.7)
			(size 1.1684 1.1684)
			(drill 0.762)
			(layers "*.Cu" "*.Mask")
			(remove_unused_layers no)
			(net "GND")
			(clearance 0.0508)
			(thermal_gap 0.0508)
		)
		(pad "P7" thru_hole circle
			(at 0 15.24)
			(size 1.1684 1.1684)
			(drill 0.762)
			(layers "*.Cu" "*.Mask")
			(remove_unused_layers no)
			(net "GND")
			(clearance 0.0508)
			(thermal_gap 0.0508)
		)
		(pad "P8" thru_hole circle
			(at 0 17.78)
			(size 1.1684 1.1684)
			(drill 0.762)
			(layers "*.Cu" "*.Mask")
			(remove_unused_layers no)
			(net "GND")
			(clearance 0.0508)
			(thermal_gap 0.0508)
		)
		(pad "P9" thru_hole circle
			(at 0 20.32)
			(size 1.1684 1.1684)
			(drill 0.762)
			(layers "*.Cu" "*.Mask")
			(remove_unused_layers no)
			(net "P12V")
			(clearance 0.0508)
			(thermal_gap 0.0508)
		)
		(pad "P10" thru_hole circle
			(at 0 22.86)
			(size 1.1684 1.1684)
			(drill 0.762)
			(layers "*.Cu" "*.Mask")
			(remove_unused_layers no)
			(net "P12V")
			(clearance 0.0508)
			(thermal_gap 0.0508)
		)
		(pad "P11" thru_hole circle
			(at 0 25.4)
			(size 1.1684 1.1684)
			(drill 0.762)
			(layers "*.Cu" "*.Mask")
			(remove_unused_layers no)
			(net "P12V")
			(clearance 0.0508)
			(thermal_gap 0.0508)
		)
		(pad "P12" thru_hole circle
			(at 0 27.94)
			(size 1.1684 1.1684)
			(drill 0.762)
			(layers "*.Cu" "*.Mask")
			(remove_unused_layers no)
			(net "P12V")
			(clearance 0.0508)
			(thermal_gap 0.0508)
		)
		(pad "P13" thru_hole circle
			(at 0 30.48)
			(size 1.1684 1.1684)
			(drill 0.762)
			(layers "*.Cu" "*.Mask")
			(remove_unused_layers no)
			(net "P12V")
			(clearance 0.0508)
			(thermal_gap 0.0508)
		)
		(pad "P14" thru_hole circle
			(at 0 33.02)
			(size 1.1684 1.1684)
			(drill 0.762)
			(layers "*.Cu" "*.Mask")
			(remove_unused_layers no)
			(net "P12V")
			(clearance 0.0508)
			(thermal_gap 0.0508)
		)
		(pad "P15" thru_hole circle
			(at 0 35.56)
			(size 1.1684 1.1684)
			(drill 0.762)
			(layers "*.Cu" "*.Mask")
			(remove_unused_layers no)
			(net "P12V")
			(clearance 0.0508)
			(thermal_gap 0.0508)
		)
		(pad "P16" thru_hole circle
			(at 0 38.1)
			(size 1.1684 1.1684)
			(drill 0.762)
			(layers "*.Cu" "*.Mask")
			(remove_unused_layers no)
			(net "P12V")
			(clearance 0.0508)
			(thermal_gap 0.0508)
		)
		(pad "P17" thru_hole circle
			(at -2.70002 38.1)
			(size 1.1684 1.1684)
			(drill 0.762)
			(layers "*.Cu" "*.Mask")
			(remove_unused_layers no)
			(net "P12V")
			(clearance 0.0508)
			(thermal_gap 0.0508)
		)
		(pad "P18" thru_hole circle
			(at -2.70002 35.56)
			(size 1.1684 1.1684)
			(drill 0.762)
			(layers "*.Cu" "*.Mask")
			(remove_unused_layers no)
			(net "P12V")
			(clearance 0.0508)
			(thermal_gap 0.0508)
		)
		(pad "P19" thru_hole circle
			(at -2.70002 33.02)
			(size 1.1684 1.1684)
			(drill 0.762)
			(layers "*.Cu" "*.Mask")
			(remove_unused_layers no)
			(net "P12V")
			(clearance 0.0508)
			(thermal_gap 0.0508)
		)
		(pad "P20" thru_hole circle
			(at -2.70002 30.48)
			(size 1.1684 1.1684)
			(drill 0.762)
			(layers "*.Cu" "*.Mask")
			(remove_unused_layers no)
			(net "P12V")
			(clearance 0.0508)
			(thermal_gap 0.0508)
		)
		(pad "P21" thru_hole circle
			(at -2.70002 27.94)
			(size 1.1684 1.1684)
			(drill 0.762)
			(layers "*.Cu" "*.Mask")
			(remove_unused_layers no)
			(net "P12V")
			(clearance 0.0508)
			(thermal_gap 0.0508)
		)
		(pad "P22" thru_hole circle
			(at -2.70002 25.4)
			(size 1.1684 1.1684)
			(drill 0.762)
			(layers "*.Cu" "*.Mask")
			(remove_unused_layers no)
			(net "P12V")
			(clearance 0.0508)
			(thermal_gap 0.0508)
		)
		(pad "P23" thru_hole circle
			(at -2.70002 22.86)
			(size 1.1684 1.1684)
			(drill 0.762)
			(layers "*.Cu" "*.Mask")
			(remove_unused_layers no)
			(net "P12V")
			(clearance 0.0508)
			(thermal_gap 0.0508)
		)
		(pad "P24" thru_hole circle
			(at -2.70002 20.32)
			(size 1.1684 1.1684)
			(drill 0.762)
			(layers "*.Cu" "*.Mask")
			(remove_unused_layers no)
			(net "P12V")
			(clearance 0.0508)
			(thermal_gap 0.0508)
		)
		(pad "P25" thru_hole circle
			(at -2.70002 17.78)
			(size 1.1684 1.1684)
			(drill 0.762)
			(layers "*.Cu" "*.Mask")
			(remove_unused_layers no)
			(net "GND")
			(clearance 0.0508)
			(thermal_gap 0.0508)
		)
		(pad "P26" thru_hole circle
			(at -2.70002 15.24)
			(size 1.1684 1.1684)
			(drill 0.762)
			(layers "*.Cu" "*.Mask")
			(remove_unused_layers no)
			(net "GND")
			(clearance 0.0508)
			(thermal_gap 0.0508)
		)
		(pad "P27" thru_hole circle
			(at -2.70002 12.7)
			(size 1.1684 1.1684)
			(drill 0.762)
			(layers "*.Cu" "*.Mask")
			(remove_unused_layers no)
			(net "GND")
			(clearance 0.0508)
			(thermal_gap 0.0508)
		)
		(pad "P28" thru_hole circle
			(at -2.70002 10.16)
			(size 1.1684 1.1684)
			(drill 0.762)
			(layers "*.Cu" "*.Mask")
			(remove_unused_layers no)
			(net "GND")
			(clearance 0.0508)
			(thermal_gap 0.0508)
		)
		(pad "P29" thru_hole circle
			(at -2.70002 7.62)
			(size 1.1684 1.1684)
			(drill 0.762)
			(layers "*.Cu" "*.Mask")
			(remove_unused_layers no)
			(net "GND")
			(clearance 0.0508)
			(thermal_gap 0.0508)
		)
		(pad "P30" thru_hole circle
			(at -2.70002 5.08)
			(size 1.1684 1.1684)
			(drill 0.762)
			(layers "*.Cu" "*.Mask")
			(remove_unused_layers no)
			(net "GND")
			(clearance 0.0508)
			(thermal_gap 0.0508)
		)
		(pad "P31" thru_hole circle
			(at -2.70002 2.54)
			(size 1.1684 1.1684)
			(drill 0.762)
			(layers "*.Cu" "*.Mask")
			(remove_unused_layers no)
			(net "GND")
			(clearance 0.0508)
			(thermal_gap 0.0508)
		)
		(pad "P32" thru_hole circle
			(at -2.70002 0)
			(size 1.1684 1.1684)
			(drill 0.762)
			(layers "*.Cu" "*.Mask")
			(remove_unused_layers no)
			(net "GND")
			(clearance 0.0508)
			(thermal_gap 0.0508)
		)
		(pad "S1" thru_hole circle
			(at 0.55499 41.60012)
			(size 1.1684 1.1684)
			(drill 0.762)
			(layers "*.Cu" "*.Mask")
			(remove_unused_layers no)
			(net "T8_BLAD1_TXD")
			(clearance 0.0508)
			(thermal_gap 0.0508)
		)
		(pad "S2" thru_hole circle
			(at -0.71501 42.87012)
			(size 1.1684 1.1684)
			(drill 0.762)
			(layers "*.Cu" "*.Mask")
			(remove_unused_layers no)
			(net "T8_BLAD1_RXD")
			(clearance 0.0508)
			(thermal_gap 0.0508)
		)
		(pad "S3" thru_hole circle
			(at 0.55499 44.14012)
			(size 1.1684 1.1684)
			(drill 0.762)
			(layers "*.Cu" "*.Mask")
			(remove_unused_layers no)
			(net "T8_BLAD1_EN")
			(clearance 0.0508)
			(thermal_gap 0.0508)
		)
		(pad "S4" thru_hole circle
			(at -0.71501 45.41012)
			(size 1.1684 1.1684)
			(drill 0.762)
			(layers "*.Cu" "*.Mask")
			(remove_unused_layers no)
			(net "B15_PSU_ALERT_N")
			(clearance 0.0508)
			(thermal_gap 0.0508)
		)
		(pad "S5" thru_hole circle
			(at 0.55499 46.68012)
			(size 1.1684 1.1684)
			(drill 0.762)
			(layers "*.Cu" "*.Mask")
			(remove_unused_layers no)
			(net "T8_BLAD2_TXD")
			(clearance 0.0508)
			(thermal_gap 0.0508)
		)
		(pad "S6" thru_hole circle
			(at -0.71501 47.95012)
			(size 1.1684 1.1684)
			(drill 0.762)
			(layers "*.Cu" "*.Mask")
			(remove_unused_layers no)
			(net "T8_BLAD2_RXD")
			(clearance 0.0508)
			(thermal_gap 0.0508)
		)
		(pad "S7" thru_hole circle
			(at -3.25501 47.95012)
			(size 1.1684 1.1684)
			(drill 0.762)
			(layers "*.Cu" "*.Mask")
			(remove_unused_layers no)
			(net "T8_BLAD4_RXD")
			(clearance 0.0508)
			(thermal_gap 0.0508)
		)
		(pad "S8" thru_hole circle
			(at -1.98501 46.68012)
			(size 1.1684 1.1684)
			(drill 0.762)
			(layers "*.Cu" "*.Mask")
			(remove_unused_layers no)
			(net "T8_BLAD4_TXD")
			(clearance 0.0508)
			(thermal_gap 0.0508)
		)
		(pad "S9" thru_hole circle
			(at -3.25501 45.41012)
			(size 1.1684 1.1684)
			(drill 0.762)
			(layers "*.Cu" "*.Mask")
			(remove_unused_layers no)
			(net "B16_PSU_ALERT_N")
			(clearance 0.0508)
			(thermal_gap 0.0508)
		)
		(pad "S10" thru_hole circle
			(at -1.98501 44.14012)
			(size 1.1684 1.1684)
			(drill 0.762)
			(layers "*.Cu" "*.Mask")
			(remove_unused_layers no)
			(net "T8_BLAD3_EN")
			(clearance 0.0508)
			(thermal_gap 0.0508)
		)
		(pad "S11" thru_hole circle
			(at -3.25501 42.87012)
			(size 1.1684 1.1684)
			(drill 0.762)
			(layers "*.Cu" "*.Mask")
			(remove_unused_layers no)
			(net "T8_BLAD3_RXD")
			(clearance 0.0508)
			(thermal_gap 0.0508)
		)
		(pad "S12" thru_hole circle
			(at -1.98501 41.60012)
			(size 1.1684 1.1684)
			(drill 0.762)
			(layers "*.Cu" "*.Mask")
			(remove_unused_layers no)
			(net "T8_BLAD3_TXD")
			(clearance 0.0508)
			(thermal_gap 0.0508)
		)
	)
)
